(kicad_pcb
	(version 20260206)
	(generator "pcbnew")
	(generator_version "10.0")
	(general
		(thickness 1.6)
		(legacy_teardrops no)
	)
	(paper "A4")
	(title_block
		(title "01162023_DA0F0TEBIF0_F0T_Expander_BD_F_brd_V02_OCP.brd")
		(comment 1 "Grand Teton / footprint 6602 of 9728 (PEX1), pads 234-355 of 2397")
	)
	(layers
		(0 "F.Cu" signal "TOP")
		(4 "In1.Cu" signal "GND")
		(6 "In2.Cu" signal "VCC")
		(8 "In3.Cu" signal "VCC1")
		(10 "In4.Cu" signal "GND1")
		(12 "In5.Cu" signal "IN1")
		(14 "In6.Cu" signal "GND2")
		(16 "In7.Cu" signal "IN2")
		(18 "In8.Cu" signal "GND3")
		(20 "In9.Cu" signal "IN3")
		(22 "In10.Cu" signal "GND4")
		(24 "In11.Cu" signal "IN4")
		(26 "In12.Cu" signal "GND5")
		(28 "In13.Cu" signal "IN5")
		(30 "In14.Cu" signal "GND6")
		(32 "In15.Cu" signal "IN6")
		(34 "In16.Cu" signal "GND7")
		(2 "B.Cu" signal "BOTTOM")
		(9 "F.Adhes" user "F.Adhesive")
		(11 "B.Adhes" user "B.Adhesive")
		(13 "F.Paste" user "Package Geometry/Pastemask Top")
		(15 "B.Paste" user "Package Geometry/Pastemask Bottom")
		(5 "F.SilkS" user "Ref Des/Silkscreen Top")
		(7 "B.SilkS" user "Ref Des/Silkscreen Bottom")
		(1 "F.Mask" user "Board Geometry/Soldermask Top")
		(3 "B.Mask" user "Board Geometry/Soldermask Bottom")
		(17 "Dwgs.User" user "User.Drawings")
		(19 "Cmts.User" user "User.Comments")
		(21 "Eco1.User" user "User.Eco1")
		(23 "Eco2.User" user "User.Eco2")
		(25 "Edge.Cuts" user "Board Geometry/Outline")
		(27 "Margin" user)
		(31 "F.CrtYd" user "Package Geometry/Place Bound Top")
		(29 "B.CrtYd" user "Package Geometry/Place Bound Bottom")
		(35 "F.Fab" user "Ref Des/Assembly Top")
		(33 "B.Fab" user "Ref Des/Assembly Bottom")
	)
	(footprint ""
		(layer "F.Cu")
		(at 175.749966 -295.89984)
		(property "Reference" "PEX1"
			(at -3.353562 35.593274 0)
			(unlocked yes)
			(layer "F.SilkS")
			(effects
				(font
					(size 2.032 1.524)
					(thickness 0.1524)
				)
				(justify left)
			)
		)
		(property "Value" ""
			(at 0 0 0)
			(layer "F.Fab")
			(effects
				(font
					(size 1.27 1.27)
				)
			)
		)
		(duplicate_pad_numbers_are_jumpers no)
		(pad "AD40" smd circle
			(at 14.249908 -0.94996)
			(size 0.4572 0.4572)
			(layers "F.Cu" "F.Mask" "F.Paste")
			(net "GND")
		)
		(pad "AD41" smd circle
			(at 15.200122 -0.94996)
			(size 0.4572 0.4572)
			(layers "F.Cu" "F.Mask" "F.Paste")
			(net "Net_1421")
		)
		(pad "AD42" smd circle
			(at 16.150082 -0.94996)
			(size 0.4572 0.4572)
			(layers "F.Cu" "F.Mask" "F.Paste")
			(net "Net_1403")
		)
		(pad "AD43" smd circle
			(at 17.100042 -0.94996)
			(size 0.4572 0.4572)
			(layers "F.Cu" "F.Mask" "F.Paste")
			(net "GND")
		)
		(pad "AD44" smd circle
			(at 18.050002 -0.94996)
			(size 0.4572 0.4572)
			(layers "F.Cu" "F.Mask" "F.Paste")
			(net "GND")
		)
		(pad "AD45" smd circle
			(at 18.999962 -0.94996)
			(size 0.4572 0.4572)
			(layers "F.Cu" "F.Mask" "F.Paste")
			(net "GND")
		)
		(pad "AD46" smd circle
			(at 19.949922 -0.94996)
			(size 0.4572 0.4572)
			(layers "F.Cu" "F.Mask" "F.Paste")
			(net "GND")
		)
		(pad "AD47" smd circle
			(at 20.899882 -0.94996)
			(size 0.4572 0.4572)
			(layers "F.Cu" "F.Mask" "F.Paste")
			(net "GND")
		)
		(pad "AD48" smd circle
			(at 21.850096 -0.94996)
			(size 0.4572 0.4572)
			(layers "F.Cu" "F.Mask" "F.Paste")
			(net "Net_1580")
		)
		(pad "AD49" smd circle
			(at 22.800056 -0.94996)
			(size 0.4572 0.4572)
			(layers "F.Cu" "F.Mask" "F.Paste")
			(net "Net_1624")
		)
		(pad "AE1" smd circle
			(at -22.800056 0)
			(size 0.4572 0.4572)
			(layers "F.Cu" "F.Mask" "F.Paste")
			(net "CLK_100M_DB800ZL_PEX1_S3_R_DN")
		)
		(pad "AE2" smd circle
			(at -21.850096 0)
			(size 0.4572 0.4572)
			(layers "F.Cu" "F.Mask" "F.Paste")
			(net "CLK_100M_DB800ZL_PEX1_S3_R_DP")
		)
		(pad "AE3" smd circle
			(at -20.899882 0)
			(size 0.4572 0.4572)
			(layers "F.Cu" "F.Mask" "F.Paste")
			(net "GND")
		)
		(pad "AE4" smd circle
			(at -19.949922 0)
			(size 0.4572 0.4572)
			(layers "F.Cu" "F.Mask" "F.Paste")
			(net "GND")
		)
		(pad "AE5" smd circle
			(at -18.999962 0)
			(size 0.4572 0.4572)
			(layers "F.Cu" "F.Mask" "F.Paste")
			(net "GND")
		)
		(pad "AE6" smd circle
			(at -18.050002 0)
			(size 0.4572 0.4572)
			(layers "F.Cu" "F.Mask" "F.Paste")
			(net "GND")
		)
		(pad "AE7" smd circle
			(at -17.100042 0)
			(size 0.4572 0.4572)
			(layers "F.Cu" "F.Mask" "F.Paste")
			(net "Net_5304")
		)
		(pad "AE8" smd circle
			(at -16.150082 0)
			(size 0.4572 0.4572)
			(layers "F.Cu" "F.Mask" "F.Paste")
			(net "Net_5311")
		)
		(pad "AE9" smd circle
			(at -15.200122 0)
			(size 0.4572 0.4572)
			(layers "F.Cu" "F.Mask" "F.Paste")
			(net "GND")
		)
		(pad "AE10" smd circle
			(at -14.249908 0)
			(size 0.4572 0.4572)
			(layers "F.Cu" "F.Mask" "F.Paste")
			(net "P1V8_PEX")
		)
		(pad "AE11" smd circle
			(at -13.299948 0)
			(size 0.4572 0.4572)
			(layers "F.Cu" "F.Mask" "F.Paste")
			(net "GND")
		)
		(pad "AE12" smd circle
			(at -12.349988 0)
			(size 0.4572 0.4572)
			(layers "F.Cu" "F.Mask" "F.Paste")
			(net "GND")
		)
		(pad "AE13" smd circle
			(at -11.400028 0)
			(size 0.4572 0.4572)
			(layers "F.Cu" "F.Mask" "F.Paste")
			(net "PCEPLL3_VDDA18_PEX1")
		)
		(pad "AE14" smd circle
			(at -10.450068 0)
			(size 0.4572 0.4572)
			(layers "F.Cu" "F.Mask" "F.Paste")
			(net "GND")
		)
		(pad "AE15" smd circle
			(at -9.500108 0)
			(size 0.4572 0.4572)
			(layers "F.Cu" "F.Mask" "F.Paste")
			(net "P0V8_PEX1")
		)
		(pad "AE16" smd circle
			(at -8.549894 0)
			(size 0.4572 0.4572)
			(layers "F.Cu" "F.Mask" "F.Paste")
			(net "GND")
		)
		(pad "AE17" smd circle
			(at -7.599934 0)
			(size 0.4572 0.4572)
			(layers "F.Cu" "F.Mask" "F.Paste")
			(net "P0V8_PEX1")
		)
		(pad "AE18" smd circle
			(at -6.649974 0)
			(size 0.4572 0.4572)
			(layers "F.Cu" "F.Mask" "F.Paste")
			(net "GND")
		)
		(pad "AE19" smd circle
			(at -5.700014 0)
			(size 0.4572 0.4572)
			(layers "F.Cu" "F.Mask" "F.Paste")
			(net "P0V8_PEX1")
		)
		(pad "AE20" smd circle
			(at -4.750054 0)
			(size 0.4572 0.4572)
			(layers "F.Cu" "F.Mask" "F.Paste")
			(net "GND")
		)
		(pad "AE21" smd circle
			(at -3.800094 0)
			(size 0.4572 0.4572)
			(layers "F.Cu" "F.Mask" "F.Paste")
			(net "P0V8_PEX1")
		)
		(pad "AE22" smd circle
			(at -2.84988 0)
			(size 0.4572 0.4572)
			(layers "F.Cu" "F.Mask" "F.Paste")
			(net "GND")
		)
		(pad "AE23" smd circle
			(at -1.89992 0)
			(size 0.4572 0.4572)
			(layers "F.Cu" "F.Mask" "F.Paste")
			(net "P0V8_PEX1")
		)
		(pad "AE24" smd circle
			(at -0.94996 0)
			(size 0.4572 0.4572)
			(layers "F.Cu" "F.Mask" "F.Paste")
			(net "GND")
		)
		(pad "AE25" smd circle
			(at 0 0)
			(size 0.4572 0.4572)
			(layers "F.Cu" "F.Mask" "F.Paste")
			(net "P0V8_PEX1")
		)
		(pad "AE26" smd circle
			(at 0.94996 0)
			(size 0.4572 0.4572)
			(layers "F.Cu" "F.Mask" "F.Paste")
			(net "GND")
		)
		(pad "AE27" smd circle
			(at 1.89992 0)
			(size 0.4572 0.4572)
			(layers "F.Cu" "F.Mask" "F.Paste")
			(net "P0V8_PEX1")
		)
		(pad "AE28" smd circle
			(at 2.84988 0)
			(size 0.4572 0.4572)
			(layers "F.Cu" "F.Mask" "F.Paste")
			(net "GND")
		)
		(pad "AE29" smd circle
			(at 3.800094 0)
			(size 0.4572 0.4572)
			(layers "F.Cu" "F.Mask" "F.Paste")
			(net "P0V8_PEX1")
		)
		(pad "AE30" smd circle
			(at 4.750054 0)
			(size 0.4572 0.4572)
			(layers "F.Cu" "F.Mask" "F.Paste")
			(net "GND")
		)
		(pad "AE31" smd circle
			(at 5.700014 0)
			(size 0.4572 0.4572)
			(layers "F.Cu" "F.Mask" "F.Paste")
			(net "P0V8_PEX1")
		)
		(pad "AE32" smd circle
			(at 6.649974 0)
			(size 0.4572 0.4572)
			(layers "F.Cu" "F.Mask" "F.Paste")
			(net "GND")
		)
		(pad "AE33" smd circle
			(at 7.599934 0)
			(size 0.4572 0.4572)
			(layers "F.Cu" "F.Mask" "F.Paste")
			(net "P0V8_SERDES_VDDA_PEX1")
		)
		(pad "AE34" smd circle
			(at 8.549894 0)
			(size 0.4572 0.4572)
			(layers "F.Cu" "F.Mask" "F.Paste")
			(net "P0V8_SERDES_VDDA_PEX1")
		)
		(pad "AE35" smd circle
			(at 9.500108 0)
			(size 0.4572 0.4572)
			(layers "F.Cu" "F.Mask" "F.Paste")
			(net "GND")
		)
		(pad "AE36" smd circle
			(at 10.450068 0)
			(size 0.4572 0.4572)
			(layers "F.Cu" "F.Mask" "F.Paste")
			(net "P1V25_PEX1")
		)
		(pad "AE37" smd circle
			(at 11.400028 0)
			(size 0.4572 0.4572)
			(layers "F.Cu" "F.Mask" "F.Paste")
			(net "GND")
		)
		(pad "AE38" smd circle
			(at 12.349988 0)
			(size 0.4572 0.4572)
			(layers "F.Cu" "F.Mask" "F.Paste")
			(net "P1V25_SERDES_VDDPLL_PEX1")
		)
		(pad "AE39" smd circle
			(at 13.299948 0)
			(size 0.4572 0.4572)
			(layers "F.Cu" "F.Mask" "F.Paste")
			(net "GND")
		)
		(pad "AE40" smd circle
			(at 14.249908 0)
			(size 0.4572 0.4572)
			(layers "F.Cu" "F.Mask" "F.Paste")
			(net "GND")
		)
		(pad "AE41" smd circle
			(at 15.200122 0)
			(size 0.4572 0.4572)
			(layers "F.Cu" "F.Mask" "F.Paste")
			(net "GND")
		)
		(pad "AE42" smd circle
			(at 16.150082 0)
			(size 0.4572 0.4572)
			(layers "F.Cu" "F.Mask" "F.Paste")
			(net "GND")
		)
		(pad "AE43" smd circle
			(at 17.100042 0)
			(size 0.4572 0.4572)
			(layers "F.Cu" "F.Mask" "F.Paste")
			(net "Net_1381")
		)
		(pad "AE44" smd circle
			(at 18.050002 0)
			(size 0.4572 0.4572)
			(layers "F.Cu" "F.Mask" "F.Paste")
			(net "Net_1415")
		)
		(pad "AE45" smd circle
			(at 18.999962 0)
			(size 0.4572 0.4572)
			(layers "F.Cu" "F.Mask" "F.Paste")
			(net "GND")
		)
		(pad "AE46" smd circle
			(at 19.949922 0)
			(size 0.4572 0.4572)
			(layers "F.Cu" "F.Mask" "F.Paste")
			(net "Net_1615")
		)
		(pad "AE47" smd circle
			(at 20.899882 0)
			(size 0.4572 0.4572)
			(layers "F.Cu" "F.Mask" "F.Paste")
			(net "Net_1612")
		)
		(pad "AE48" smd circle
			(at 21.850096 0)
			(size 0.4572 0.4572)
			(layers "F.Cu" "F.Mask" "F.Paste")
			(net "GND")
		)
		(pad "AE49" smd circle
			(at 22.800056 0)
			(size 0.4572 0.4572)
			(layers "F.Cu" "F.Mask" "F.Paste")
			(net "GND")
		)
		(pad "AF1" smd circle
			(at -22.800056 0.94996)
			(size 0.4572 0.4572)
			(layers "F.Cu" "F.Mask" "F.Paste")
			(net "GND")
		)
		(pad "AF2" smd circle
			(at -21.850096 0.94996)
			(size 0.4572 0.4572)
			(layers "F.Cu" "F.Mask" "F.Paste")
			(net "GND")
		)
		(pad "AF3" smd circle
			(at -20.899882 0.94996)
			(size 0.4572 0.4572)
			(layers "F.Cu" "F.Mask" "F.Paste")
			(net "GND")
		)
		(pad "AF4" smd circle
			(at -19.949922 0.94996)
			(size 0.4572 0.4572)
			(layers "F.Cu" "F.Mask" "F.Paste")
			(net "Net_5223")
		)
		(pad "AF5" smd circle
			(at -18.999962 0.94996)
			(size 0.4572 0.4572)
			(layers "F.Cu" "F.Mask" "F.Paste")
			(net "Net_5224")
		)
		(pad "AF6" smd circle
			(at -18.050002 0.94996)
			(size 0.4572 0.4572)
			(layers "F.Cu" "F.Mask" "F.Paste")
			(net "GND")
		)
		(pad "AF7" smd circle
			(at -17.100042 0.94996)
			(size 0.4572 0.4572)
			(layers "F.Cu" "F.Mask" "F.Paste")
			(net "SPI_PEX1_SDIO0")
		)
		(pad "AF8" smd circle
			(at -16.150082 0.94996)
			(size 0.4572 0.4572)
			(layers "F.Cu" "F.Mask" "F.Paste")
			(net "SPI_PEX1_SDIO1")
		)
		(pad "AF9" smd circle
			(at -15.200122 0.94996)
			(size 0.4572 0.4572)
			(layers "F.Cu" "F.Mask" "F.Paste")
			(net "GND")
		)
		(pad "AF10" smd circle
			(at -14.249908 0.94996)
			(size 0.4572 0.4572)
			(layers "F.Cu" "F.Mask" "F.Paste")
			(net "P1V8_PEX")
		)
		(pad "AF11" smd circle
			(at -13.299948 0.94996)
			(size 0.4572 0.4572)
			(layers "F.Cu" "F.Mask" "F.Paste")
			(net "GND")
		)
		(pad "AF12" smd circle
			(at -12.349988 0.94996)
			(size 0.4572 0.4572)
			(layers "F.Cu" "F.Mask" "F.Paste")
			(net "PCEPLL4_VDDA18_PEX1")
		)
		(pad "AF13" smd circle
			(at -11.400028 0.94996)
			(size 0.4572 0.4572)
			(layers "F.Cu" "F.Mask" "F.Paste")
			(net "GND")
		)
		(pad "AF14" smd circle
			(at -10.450068 0.94996)
			(size 0.4572 0.4572)
			(layers "F.Cu" "F.Mask" "F.Paste")
			(net "P0V8_PEX1")
		)
		(pad "AF15" smd circle
			(at -9.500108 0.94996)
			(size 0.4572 0.4572)
			(layers "F.Cu" "F.Mask" "F.Paste")
			(net "GND")
		)
		(pad "AF16" smd circle
			(at -8.549894 0.94996)
			(size 0.4572 0.4572)
			(layers "F.Cu" "F.Mask" "F.Paste")
			(net "P0V8_PEX1")
		)
		(pad "AF17" smd circle
			(at -7.599934 0.94996)
			(size 0.4572 0.4572)
			(layers "F.Cu" "F.Mask" "F.Paste")
			(net "GND")
		)
		(pad "AF18" smd circle
			(at -6.649974 0.94996)
			(size 0.4572 0.4572)
			(layers "F.Cu" "F.Mask" "F.Paste")
			(net "P0V8_PEX1")
		)
		(pad "AF19" smd circle
			(at -5.700014 0.94996)
			(size 0.4572 0.4572)
			(layers "F.Cu" "F.Mask" "F.Paste")
			(net "GND")
		)
		(pad "AF20" smd circle
			(at -4.750054 0.94996)
			(size 0.4572 0.4572)
			(layers "F.Cu" "F.Mask" "F.Paste")
			(net "P0V8_PEX1")
		)
		(pad "AF21" smd circle
			(at -3.800094 0.94996)
			(size 0.4572 0.4572)
			(layers "F.Cu" "F.Mask" "F.Paste")
			(net "GND")
		)
		(pad "AF22" smd circle
			(at -2.84988 0.94996)
			(size 0.4572 0.4572)
			(layers "F.Cu" "F.Mask" "F.Paste")
			(net "P0V8_PEX1")
		)
		(pad "AF23" smd circle
			(at -1.89992 0.94996)
			(size 0.4572 0.4572)
			(layers "F.Cu" "F.Mask" "F.Paste")
			(net "GND")
		)
		(pad "AF24" smd circle
			(at -0.94996 0.94996)
			(size 0.4572 0.4572)
			(layers "F.Cu" "F.Mask" "F.Paste")
			(net "P0V8_PEX1")
		)
		(pad "AF25" smd circle
			(at 0 0.94996)
			(size 0.4572 0.4572)
			(layers "F.Cu" "F.Mask" "F.Paste")
			(net "GND")
		)
		(pad "AF26" smd circle
			(at 0.94996 0.94996)
			(size 0.4572 0.4572)
			(layers "F.Cu" "F.Mask" "F.Paste")
			(net "P0V8_PEX1")
		)
		(pad "AF27" smd circle
			(at 1.89992 0.94996)
			(size 0.4572 0.4572)
			(layers "F.Cu" "F.Mask" "F.Paste")
			(net "GND")
		)
		(pad "AF28" smd circle
			(at 2.84988 0.94996)
			(size 0.4572 0.4572)
			(layers "F.Cu" "F.Mask" "F.Paste")
			(net "P0V8_PEX1")
		)
		(pad "AF29" smd circle
			(at 3.800094 0.94996)
			(size 0.4572 0.4572)
			(layers "F.Cu" "F.Mask" "F.Paste")
			(net "GND")
		)
		(pad "AF30" smd circle
			(at 4.750054 0.94996)
			(size 0.4572 0.4572)
			(layers "F.Cu" "F.Mask" "F.Paste")
			(net "P0V8_PEX1")
		)
		(pad "AF31" smd circle
			(at 5.700014 0.94996)
			(size 0.4572 0.4572)
			(layers "F.Cu" "F.Mask" "F.Paste")
			(net "GND")
		)
		(pad "AF32" smd circle
			(at 6.649974 0.94996)
			(size 0.4572 0.4572)
			(layers "F.Cu" "F.Mask" "F.Paste")
			(net "P0V8_SERDES_VDDA_PEX1")
		)
		(pad "AF33" smd circle
			(at 7.599934 0.94996)
			(size 0.4572 0.4572)
			(layers "F.Cu" "F.Mask" "F.Paste")
			(net "P0V8_SERDES_VDDA_PEX1")
		)
		(pad "AF34" smd circle
			(at 8.549894 0.94996)
			(size 0.4572 0.4572)
			(layers "F.Cu" "F.Mask" "F.Paste")
			(net "P0V8_SERDES_VDDA_PEX1")
		)
		(pad "AF35" smd circle
			(at 9.500108 0.94996)
			(size 0.4572 0.4572)
			(layers "F.Cu" "F.Mask" "F.Paste")
			(net "GND")
		)
		(pad "AF36" smd circle
			(at 10.450068 0.94996)
			(size 0.4572 0.4572)
			(layers "F.Cu" "F.Mask" "F.Paste")
			(net "P1V25_PEX1")
		)
		(pad "AF37" smd circle
			(at 11.400028 0.94996)
			(size 0.4572 0.4572)
			(layers "F.Cu" "F.Mask" "F.Paste")
			(net "GND")
		)
		(pad "AF38" smd circle
			(at 12.349988 0.94996)
			(size 0.4572 0.4572)
			(layers "F.Cu" "F.Mask" "F.Paste")
			(net "P1V25_SERDES_VDDPLL_PEX1")
		)
		(pad "AF39" smd circle
			(at 13.299948 0.94996)
			(size 0.4572 0.4572)
			(layers "F.Cu" "F.Mask" "F.Paste")
			(net "GND")
		)
		(pad "AF40" smd circle
			(at 14.249908 0.94996)
			(size 0.4572 0.4572)
			(layers "F.Cu" "F.Mask" "F.Paste")
			(net "GND")
		)
		(pad "AF41" smd circle
			(at 15.200122 0.94996)
			(size 0.4572 0.4572)
			(layers "F.Cu" "F.Mask" "F.Paste")
			(net "Net_1372")
		)
		(pad "AF42" smd circle
			(at 16.150082 0.94996)
			(size 0.4572 0.4572)
			(layers "F.Cu" "F.Mask" "F.Paste")
			(net "Net_1369")
		)
		(pad "AF43" smd circle
			(at 17.100042 0.94996)
			(size 0.4572 0.4572)
			(layers "F.Cu" "F.Mask" "F.Paste")
			(net "GND")
		)
		(pad "AF44" smd circle
			(at 18.050002 0.94996)
			(size 0.4572 0.4572)
			(layers "F.Cu" "F.Mask" "F.Paste")
			(net "GND")
		)
		(pad "AF45" smd circle
			(at 18.999962 0.94996)
			(size 0.4572 0.4572)
			(layers "F.Cu" "F.Mask" "F.Paste")
			(net "GND")
		)
		(pad "AF46" smd circle
			(at 19.949922 0.94996)
			(size 0.4572 0.4572)
			(layers "F.Cu" "F.Mask" "F.Paste")
			(net "GND")
		)
		(pad "AF47" smd circle
			(at 20.899882 0.94996)
			(size 0.4572 0.4572)
			(layers "F.Cu" "F.Mask" "F.Paste")
			(net "GND")
		)
		(pad "AF48" smd circle
			(at 21.850096 0.94996)
			(size 0.4572 0.4572)
			(layers "F.Cu" "F.Mask" "F.Paste")
			(net "Net_1627")
		)
		(pad "AF49" smd circle
			(at 22.800056 0.94996)
			(size 0.4572 0.4572)
			(layers "F.Cu" "F.Mask" "F.Paste")
			(net "Net_1529")
		)
		(pad "AG1" smd circle
			(at -22.800056 1.89992)
			(size 0.4572 0.4572)
			(layers "F.Cu" "F.Mask" "F.Paste")
			(net "Net_5226")
		)
		(pad "AG2" smd circle
			(at -21.850096 1.89992)
			(size 0.4572 0.4572)
			(layers "F.Cu" "F.Mask" "F.Paste")
			(net "Net_5227")
		)
		(pad "AG3" smd circle
			(at -20.899882 1.89992)
			(size 0.4572 0.4572)
			(layers "F.Cu" "F.Mask" "F.Paste")
			(net "GND")
		)
		(pad "AG4" smd circle
			(at -19.949922 1.89992)
			(size 0.4572 0.4572)
			(layers "F.Cu" "F.Mask" "F.Paste")
			(net "GND")
		)
		(pad "AG5" smd circle
			(at -18.999962 1.89992)
			(size 0.4572 0.4572)
			(layers "F.Cu" "F.Mask" "F.Paste")
			(net "GND")
		)
		(pad "AG6" smd circle
			(at -18.050002 1.89992)
			(size 0.4572 0.4572)
			(layers "F.Cu" "F.Mask" "F.Paste")
			(net "GND")
		)
		(pad "AG7" smd circle
			(at -17.100042 1.89992)
			(size 0.4572 0.4572)
			(layers "F.Cu" "F.Mask" "F.Paste")
			(net "SPI_PEX1_RST_N")
		)
		(pad "AG8" smd circle
			(at -16.150082 1.89992)
			(size 0.4572 0.4572)
			(layers "F.Cu" "F.Mask" "F.Paste")
			(net "SPI_PEX1_SDIO2")
		)
		(pad "AG9" smd circle
			(at -15.200122 1.89992)
			(size 0.4572 0.4572)
			(layers "F.Cu" "F.Mask" "F.Paste")
			(net "GND")
		)
		(pad "AG10" smd circle
			(at -14.249908 1.89992)
			(size 0.4572 0.4572)
			(layers "F.Cu" "F.Mask" "F.Paste")
			(net "GND")
		)
		(pad "AG11" smd circle
			(at -13.299948 1.89992)
			(size 0.4572 0.4572)
			(layers "F.Cu" "F.Mask" "F.Paste")
			(net "GND")
		)
		(pad "AG12" smd circle
			(at -12.349988 1.89992)
			(size 0.4572 0.4572)
			(layers "F.Cu" "F.Mask" "F.Paste")
			(net "GND")
		)
		(pad "AG13" smd circle
			(at -11.400028 1.89992)
			(size 0.4572 0.4572)
			(layers "F.Cu" "F.Mask" "F.Paste")
			(net "PCEPLL5_VDDA18_PEX1")
		)
		(pad "AG14" smd circle
			(at -10.450068 1.89992)
			(size 0.4572 0.4572)
			(layers "F.Cu" "F.Mask" "F.Paste")
			(net "GND")
		)
	)
)
